#ISCELL
  mstr_misc dns *
  *
#ISCELL
  pure_quanta quanta_title_block_c *
  *
#CELL
  pure_quanta ds125br111rtwr *
  page111_i1
#ISCELL
  standard offpage *
  page111_i10
#ISCELL
  standard offpage *
  page111_i11
#CELL
  pure_quanta q_res *
  page111_i12
#ISCELL
  pure_quanta_power universal_gnd *
  page111_i13
#ISCELL
  standard offpage *
  page111_i14
#ISCELL
  standard offpage *
  page111_i15
#ISCELL
  standard offpage *
  page111_i16
#ISCELL
  standard offpage *
  page111_i17
#ISCELL
  standard offpage *
  page111_i18
#ISCELL
  standard offpage *
  page111_i19
#ISCELL
  pure_quanta_power universal_power *
  page111_i2
#ISCELL
  standard offpage *
  page111_i20
#ISCELL
  standard offpage *
  page111_i21
#ISCELL
  standard offpage *
  page111_i22
#CELL
  pure_quanta q_res *
  page111_i23
#ISCELL
  standard offpage *
  page111_i24
#ISCELL
  standard offpage *
  page111_i25
#ISCELL
  standard offpage *
  page111_i26
#ISCELL
  standard offpage *
  page111_i27
#ISCELL
  standard offpage *
  page111_i28
#ISCELL
  pure_quanta_power universal_gnd *
  page111_i29
#CELL
  pure_quanta q_cap *
  page111_i3
#ISCELL
  pure_quanta_power universal_power *
  page111_i30
#CELL
  pure_quanta q_res *
  page111_i32
#ISCELL
  pure_quanta_power universal_gnd *
  page111_i35
#ISCELL
  pure_quanta_power universal_gnd *
  page111_i36
#ISCELL
  standard offpage *
  page111_i37
#ISCELL
  standard offpage *
  page111_i38
#CELL
  pure_quanta q_res *
  page111_i39
#ISCELL
  pure_quanta_power universal_gnd *
  page111_i4
#CELL
  pure_quanta q_res *
  page111_i40
#CELL
  pure_quanta q_res *
  page111_i41
#ISCELL
  standard offpage *
  page111_i42
#ISCELL
  standard offpage *
  page111_i43
#CELL
  pure_quanta q_res *
  page111_i44
#CELL
  pure_quanta q_res *
  page111_i45
#ISCELL
  pure_quanta_power universal_gnd *
  page111_i46
#ISCELL
  pure_quanta_power universal_power *
  page111_i47
#CELL
  pure_quanta q_res *
  page111_i48
#CELL
  pure_quanta q_res *
  page111_i49
#CELL
  pure_quanta q_cap *
  page111_i5
#ISCELL
  pure_quanta_power universal_gnd *
  page111_i50
#ISCELL
  standard offpage *
  page111_i51
#ISCELL
  standard offpage *
  page111_i52
#CELL
  pure_quanta q_res *
  page111_i53
#ISCELL
  pure_quanta_power universal_gnd *
  page111_i55
#ISCELL
  pure_quanta_power universal_power *
  page111_i56
#CELL
  pure_quanta q_res *
  page111_i57
#CELL
  pure_quanta q_res *
  page111_i58
#ISCELL
  pure_quanta_power universal_gnd *
  page111_i59
#CELL
  pure_quanta q_cap *
  page111_i6
#CELL
  pure_quanta q_res *
  page111_i60
#ISCELL
  standard offpage *
  page111_i61
#CELL
  pure_quanta q_res *
  page111_i63
#CELL
  pure_quanta q_res *
  page111_i64
#ISCELL
  pure_quanta_power universal_gnd *
  page111_i65
#ISCELL
  pure_quanta_power universal_power *
  page111_i66
#ISCELL
  pure_quanta_power universal_gnd *
  page111_i67
#CELL
  pure_quanta q_res *
  page111_i68
#CELL
  pure_quanta q_cap *
  page111_i7
#ISCELL
  pure_quanta_power universal_power *
  page111_i70
#ISCELL
  standard offpage *
  page111_i71
#ISCELL
  pure_quanta_power universal_gnd *
  page111_i72
#CELL
  pure_quanta q_res *
  page111_i73
#ISCELL
  pure_quanta_power universal_power *
  page111_i75
#ISCELL
  standard offpage *
  page111_i76
#CELL
  pure_quanta q_res *
  page111_i77
#CELL
  pure_quanta q_res *
  page111_i78
#ISCELL
  standard offpage *
  page111_i8
#ISCELL
  standard offpage *
  page111_i9
